(kicad_pcb
	(version 20260206)
	(generator "pcbnew")
	(generator_version "10.0")
	(general
		(thickness 1.6)
		(legacy_teardrops no)
	)
	(paper "A4")
	(title_block
		(title "01162023_DA0F0TEBIF0_F0T_Expander_BD_F_brd_V02_OCP.brd")
		(comment 1 "Grand Teton / footprints 157-165 of 9728")
	)
	(layers
		(0 "F.Cu" signal "TOP")
		(4 "In1.Cu" signal "GND")
		(6 "In2.Cu" signal "VCC")
		(8 "In3.Cu" signal "VCC1")
		(10 "In4.Cu" signal "GND1")
		(12 "In5.Cu" signal "IN1")
		(14 "In6.Cu" signal "GND2")
		(16 "In7.Cu" signal "IN2")
		(18 "In8.Cu" signal "GND3")
		(20 "In9.Cu" signal "IN3")
		(22 "In10.Cu" signal "GND4")
		(24 "In11.Cu" signal "IN4")
		(26 "In12.Cu" signal "GND5")
		(28 "In13.Cu" signal "IN5")
		(30 "In14.Cu" signal "GND6")
		(32 "In15.Cu" signal "IN6")
		(34 "In16.Cu" signal "GND7")
		(2 "B.Cu" signal "BOTTOM")
		(9 "F.Adhes" user "F.Adhesive")
		(11 "B.Adhes" user "B.Adhesive")
		(13 "F.Paste" user "Package Geometry/Pastemask Top")
		(15 "B.Paste" user "Package Geometry/Pastemask Bottom")
		(5 "F.SilkS" user "Ref Des/Silkscreen Top")
		(7 "B.SilkS" user "Ref Des/Silkscreen Bottom")
		(1 "F.Mask" user "Board Geometry/Soldermask Top")
		(3 "B.Mask" user "Board Geometry/Soldermask Bottom")
		(17 "Dwgs.User" user "User.Drawings")
		(19 "Cmts.User" user "User.Comments")
		(21 "Eco1.User" user "User.Eco1")
		(23 "Eco2.User" user "User.Eco2")
		(25 "Edge.Cuts" user "Board Geometry/Outline")
		(27 "Margin" user)
		(31 "F.CrtYd" user "Package Geometry/Place Bound Top")
		(29 "B.CrtYd" user "Package Geometry/Place Bound Bottom")
		(35 "F.Fab" user "Ref Des/Assembly Top")
		(33 "B.Fab" user "Ref Des/Assembly Bottom")
	)
	(footprint ""
		(layer "F.Cu")
		(at 452.567802 -56.353456)
		(property "Reference" "C2876"
			(at 0 0 0)
			(layer "F.SilkS")
			(hide yes)
			(effects
				(font
					(size 1.27 1.27)
				)
			)
		)
		(property "Value" ""
			(at 0 0 0)
			(layer "F.Fab")
			(effects
				(font
					(size 1.27 1.27)
				)
			)
		)
		(duplicate_pad_numbers_are_jumpers no)
		(fp_line
			(start -0.7874 -0.4064)
			(end 0.7874 -0.4064)
			(stroke
				(width 0.1524)
				(type default)
			)
			(layer "F.SilkS")
		)
		(fp_line
			(start -0.7874 0.4064)
			(end -0.7874 -0.4064)
			(stroke
				(width 0.1524)
				(type default)
			)
			(layer "F.SilkS")
		)
		(fp_line
			(start 0.7874 -0.4064)
			(end 0.7874 0.4064)
			(stroke
				(width 0.1524)
				(type default)
			)
			(layer "F.SilkS")
		)
		(fp_line
			(start 0.7874 0.4064)
			(end -0.7874 0.4064)
			(stroke
				(width 0.1524)
				(type default)
			)
			(layer "F.SilkS")
		)
		(fp_line
			(start -0.67945 -0.305054)
			(end -0.12065 -0.305054)
			(stroke
				(width 0.1)
				(type default)
			)
			(layer "F.Fab")
		)
		(fp_line
			(start -0.67945 0.3048)
			(end -0.67945 -0.305054)
			(stroke
				(width 0.1)
				(type default)
			)
			(layer "F.Fab")
		)
		(fp_line
			(start -0.12065 -0.305054)
			(end -0.12065 -0.2794)
			(stroke
				(width 0.1)
				(type default)
			)
			(layer "F.Fab")
		)
		(fp_line
			(start -0.12065 -0.2794)
			(end 0.12065 -0.2794)
			(stroke
				(width 0.1)
				(type default)
			)
			(layer "F.Fab")
		)
		(fp_line
			(start -0.12065 0.2794)
			(end -0.12065 0.3048)
			(stroke
				(width 0.1)
				(type default)
			)
			(layer "F.Fab")
		)
		(fp_line
			(start -0.12065 0.3048)
			(end -0.67945 0.3048)
			(stroke
				(width 0.1)
				(type default)
			)
			(layer "F.Fab")
		)
		(fp_line
			(start 0.120396 0.2794)
			(end -0.12065 0.2794)
			(stroke
				(width 0.1)
				(type default)
			)
			(layer "F.Fab")
		)
		(fp_line
			(start 0.120396 0.3048)
			(end 0.120396 0.2794)
			(stroke
				(width 0.1)
				(type default)
			)
			(layer "F.Fab")
		)
		(fp_line
			(start 0.12065 -0.3048)
			(end 0.67945 -0.3048)
			(stroke
				(width 0.1)
				(type default)
			)
			(layer "F.Fab")
		)
		(fp_line
			(start 0.12065 -0.2794)
			(end 0.12065 -0.3048)
			(stroke
				(width 0.1)
				(type default)
			)
			(layer "F.Fab")
		)
		(fp_line
			(start 0.67945 -0.3048)
			(end 0.67945 0.3048)
			(stroke
				(width 0.1)
				(type default)
			)
			(layer "F.Fab")
		)
		(fp_line
			(start 0.67945 0.3048)
			(end 0.120396 0.3048)
			(stroke
				(width 0.1)
				(type default)
			)
			(layer "F.Fab")
		)
		(pad "1" smd circle
			(at -0.40005 0)
			(size 0 0)
			(layers "F.Cu" "F.Mask" "F.Paste")
			(net "SSD15_PWR_EN_R")
		)
		(pad "2" smd circle
			(at 0.40005 0)
			(size 0 0)
			(layers "F.Cu" "F.Mask" "F.Paste")
			(net "GND")
		)
	)
	(footprint ""
		(layer "F.Cu")
		(at 445.55791 -72.766682 90)
		(property "Reference" "PC893"
			(at 0 0 90)
			(layer "F.SilkS")
			(hide yes)
			(effects
				(font
					(size 1.27 1.27)
				)
			)
		)
		(property "Value" ""
			(at 0 0 90)
			(layer "F.Fab")
			(effects
				(font
					(size 1.27 1.27)
				)
			)
		)
		(duplicate_pad_numbers_are_jumpers no)
		(fp_line
			(start 0.7874 -0.4064)
			(end 0.7874 0.4064)
			(stroke
				(width 0.1524)
				(type default)
			)
			(layer "F.SilkS")
		)
		(fp_line
			(start -0.7874 -0.4064)
			(end 0.7874 -0.4064)
			(stroke
				(width 0.1524)
				(type default)
			)
			(layer "F.SilkS")
		)
		(fp_line
			(start 0.7874 0.4064)
			(end -0.7874 0.4064)
			(stroke
				(width 0.1524)
				(type default)
			)
			(layer "F.SilkS")
		)
		(fp_line
			(start -0.7874 0.4064)
			(end -0.7874 -0.4064)
			(stroke
				(width 0.1524)
				(type default)
			)
			(layer "F.SilkS")
		)
		(fp_line
			(start -0.12065 -0.305054)
			(end -0.12065 -0.2794)
			(stroke
				(width 0.1)
				(type default)
			)
			(layer "F.Fab")
		)
		(fp_line
			(start -0.67945 -0.305054)
			(end -0.12065 -0.305054)
			(stroke
				(width 0.1)
				(type default)
			)
			(layer "F.Fab")
		)
		(fp_line
			(start 0.67945 -0.3048)
			(end 0.67945 0.3048)
			(stroke
				(width 0.1)
				(type default)
			)
			(layer "F.Fab")
		)
		(fp_line
			(start 0.12065 -0.3048)
			(end 0.67945 -0.3048)
			(stroke
				(width 0.1)
				(type default)
			)
			(layer "F.Fab")
		)
		(fp_line
			(start 0.12065 -0.2794)
			(end 0.12065 -0.3048)
			(stroke
				(width 0.1)
				(type default)
			)
			(layer "F.Fab")
		)
		(fp_line
			(start -0.12065 -0.2794)
			(end 0.12065 -0.2794)
			(stroke
				(width 0.1)
				(type default)
			)
			(layer "F.Fab")
		)
		(fp_line
			(start 0.120396 0.2794)
			(end -0.12065 0.2794)
			(stroke
				(width 0.1)
				(type default)
			)
			(layer "F.Fab")
		)
		(fp_line
			(start -0.12065 0.2794)
			(end -0.12065 0.3048)
			(stroke
				(width 0.1)
				(type default)
			)
			(layer "F.Fab")
		)
		(fp_line
			(start 0.67945 0.3048)
			(end 0.120396 0.3048)
			(stroke
				(width 0.1)
				(type default)
			)
			(layer "F.Fab")
		)
		(fp_line
			(start 0.120396 0.3048)
			(end 0.120396 0.2794)
			(stroke
				(width 0.1)
				(type default)
			)
			(layer "F.Fab")
		)
		(fp_line
			(start -0.12065 0.3048)
			(end -0.67945 0.3048)
			(stroke
				(width 0.1)
				(type default)
			)
			(layer "F.Fab")
		)
		(fp_line
			(start -0.67945 0.3048)
			(end -0.67945 -0.305054)
			(stroke
				(width 0.1)
				(type default)
			)
			(layer "F.Fab")
		)
		(pad "1" smd circle
			(at -0.40005 0 90)
			(size 0 0)
			(layers "F.Cu" "F.Mask" "F.Paste")
			(net "P12V_SSD15_CO_MODE")
		)
		(pad "2" smd circle
			(at 0.40005 0 90)
			(size 0 0)
			(layers "F.Cu" "F.Mask" "F.Paste")
			(net "GND")
		)
	)
	(footprint ""
		(layer "F.Cu")
		(at 312.21934 -118.670324 180)
		(property "Reference" "C454"
			(at 0 0 180)
			(layer "F.SilkS")
			(hide yes)
			(effects
				(font
					(size 1.27 1.27)
				)
			)
		)
		(property "Value" ""
			(at 0 0 180)
			(layer "F.Fab")
			(effects
				(font
					(size 1.27 1.27)
				)
			)
		)
		(duplicate_pad_numbers_are_jumpers no)
		(fp_line
			(start 0.299974 0.150114)
			(end -0.299974 0.150114)
			(stroke
				(width 0.1)
				(type default)
			)
			(layer "F.Fab")
		)
		(fp_line
			(start 0.299974 -0.150114)
			(end 0.299974 0.150114)
			(stroke
				(width 0.1)
				(type default)
			)
			(layer "F.Fab")
		)
		(fp_line
			(start -0.299974 0.150114)
			(end -0.299974 -0.150114)
			(stroke
				(width 0.1)
				(type default)
			)
			(layer "F.Fab")
		)
		(fp_line
			(start -0.299974 -0.150114)
			(end 0.299974 -0.150114)
			(stroke
				(width 0.1)
				(type default)
			)
			(layer "F.Fab")
		)
		(pad "1" smd rect
			(at -0.2667 0 180)
			(size 0.3048 0.381)
			(layers "F.Cu" "F.Mask" "F.Paste")
			(net "P5E_PEX2_STN0_TX_DN<0>")
		)
		(pad "2" smd rect
			(at 0.2667 0 180)
			(size 0.3048 0.381)
			(layers "F.Cu" "F.Mask" "F.Paste")
			(net "P5E_PEX2_STN0_TX_C_DN<0>")
		)
	)
	(footprint ""
		(layer "F.Cu")
		(at 104.009952 -407.599896)
		(property "Reference" "H50"
			(at -4.538218 -5.058918 0)
			(unlocked yes)
			(layer "F.SilkS")
			(effects
				(font
					(size 0.7874 0.5842)
					(thickness 0.1524)
				)
				(justify left)
			)
		)
		(property "Value" ""
			(at 0 0 0)
			(layer "F.Fab")
			(effects
				(font
					(size 1.27 1.27)
				)
			)
		)
		(duplicate_pad_numbers_are_jumpers no)
		(pad "1" thru_hole circle
			(at 0 0)
			(size 10.0076 10.0076)
			(drill 5.6134)
			(layers "*.Cu" "*.Mask")
			(remove_unused_layers no)
			(net "GND")
			(clearance -1.9431)
		)
	)
	(footprint ""
		(layer "F.Cu")
		(at 55.8292 -117.5512)
		(property "Reference" "R6"
			(at 0 0 0)
			(layer "F.SilkS")
			(hide yes)
			(effects
				(font
					(size 1.27 1.27)
				)
			)
		)
		(property "Value" ""
			(at 0 0 0)
			(layer "F.Fab")
			(effects
				(font
					(size 1.27 1.27)
				)
			)
		)
		(duplicate_pad_numbers_are_jumpers no)
		(fp_line
			(start -0.7874 -0.4064)
			(end 0.7874 -0.4064)
			(stroke
				(width 0.1524)
				(type default)
			)
			(layer "F.SilkS")
		)
		(fp_line
			(start -0.7874 0.4064)
			(end -0.7874 -0.4064)
			(stroke
				(width 0.1524)
				(type default)
			)
			(layer "F.SilkS")
		)
		(fp_line
			(start 0.7874 -0.4064)
			(end 0.7874 0.4064)
			(stroke
				(width 0.1524)
				(type default)
			)
			(layer "F.SilkS")
		)
		(fp_line
			(start 0.7874 0.4064)
			(end -0.7874 0.4064)
			(stroke
				(width 0.1524)
				(type default)
			)
			(layer "F.SilkS")
		)
		(fp_line
			(start -0.67945 -0.305054)
			(end -0.12065 -0.305054)
			(stroke
				(width 0.1)
				(type default)
			)
			(layer "F.Fab")
		)
		(fp_line
			(start -0.67945 0.3048)
			(end -0.67945 -0.305054)
			(stroke
				(width 0.1)
				(type default)
			)
			(layer "F.Fab")
		)
		(fp_line
			(start -0.12065 -0.305054)
			(end -0.12065 -0.2794)
			(stroke
				(width 0.1)
				(type default)
			)
			(layer "F.Fab")
		)
		(fp_line
			(start -0.12065 -0.2794)
			(end 0.12065 -0.2794)
			(stroke
				(width 0.1)
				(type default)
			)
			(layer "F.Fab")
		)
		(fp_line
			(start -0.12065 0.2794)
			(end -0.12065 0.3048)
			(stroke
				(width 0.1)
				(type default)
			)
			(layer "F.Fab")
		)
		(fp_line
			(start -0.12065 0.3048)
			(end -0.67945 0.3048)
			(stroke
				(width 0.1)
				(type default)
			)
			(layer "F.Fab")
		)
		(fp_line
			(start 0.120396 0.2794)
			(end -0.12065 0.2794)
			(stroke
				(width 0.1)
				(type default)
			)
			(layer "F.Fab")
		)
		(fp_line
			(start 0.120396 0.3048)
			(end 0.120396 0.2794)
			(stroke
				(width 0.1)
				(type default)
			)
			(layer "F.Fab")
		)
		(fp_line
			(start 0.12065 -0.3048)
			(end 0.67945 -0.3048)
			(stroke
				(width 0.1)
				(type default)
			)
			(layer "F.Fab")
		)
		(fp_line
			(start 0.12065 -0.2794)
			(end 0.12065 -0.3048)
			(stroke
				(width 0.1)
				(type default)
			)
			(layer "F.Fab")
		)
		(fp_line
			(start 0.67945 -0.3048)
			(end 0.67945 0.3048)
			(stroke
				(width 0.1)
				(type default)
			)
			(layer "F.Fab")
		)
		(fp_line
			(start 0.67945 0.3048)
			(end 0.120396 0.3048)
			(stroke
				(width 0.1)
				(type default)
			)
			(layer "F.Fab")
		)
		(pad "1" smd circle
			(at -0.40005 0)
			(size 0 0)
			(layers "F.Cu" "F.Mask" "F.Paste")
			(net "PRSNTB1_NIC0_N")
		)
		(pad "2" smd circle
			(at 0.40005 0)
			(size 0 0)
			(layers "F.Cu" "F.Mask" "F.Paste")
			(net "P3V3_AUX")
		)
	)
	(footprint ""
		(layer "F.Cu")
		(at 371.16258 -350.098614 90)
		(property "Reference" "C778"
			(at 0 0 90)
			(layer "F.SilkS")
			(hide yes)
			(effects
				(font
					(size 1.27 1.27)
				)
			)
		)
		(property "Value" ""
			(at 0 0 90)
			(layer "F.Fab")
			(effects
				(font
					(size 1.27 1.27)
				)
			)
		)
		(duplicate_pad_numbers_are_jumpers no)
		(fp_line
			(start 0.299974 -0.150114)
			(end 0.299974 0.150114)
			(stroke
				(width 0.1)
				(type default)
			)
			(layer "F.Fab")
		)
		(fp_line
			(start -0.299974 -0.150114)
			(end 0.299974 -0.150114)
			(stroke
				(width 0.1)
				(type default)
			)
			(layer "F.Fab")
		)
		(fp_line
			(start 0.299974 0.150114)
			(end -0.299974 0.150114)
			(stroke
				(width 0.1)
				(type default)
			)
			(layer "F.Fab")
		)
		(fp_line
			(start -0.299974 0.150114)
			(end -0.299974 -0.150114)
			(stroke
				(width 0.1)
				(type default)
			)
			(layer "F.Fab")
		)
		(pad "1" smd rect
			(at -0.2667 0 90)
			(size 0.3048 0.381)
			(layers "F.Cu" "F.Mask" "F.Paste")
			(net "P5E_PEX3_STN6_TX_DP<103>")
		)
		(pad "2" smd rect
			(at 0.2667 0 90)
			(size 0.3048 0.381)
			(layers "F.Cu" "F.Mask" "F.Paste")
			(net "P5E_PEX3_STN6_TX_C_DP<103>")
		)
	)
	(footprint ""
		(layer "F.Cu")
		(at 241.51971 -162.003994 90)
		(property "Reference" "PR7033"
			(at 0 0 90)
			(layer "F.SilkS")
			(hide yes)
			(effects
				(font
					(size 1.27 1.27)
				)
			)
		)
		(property "Value" ""
			(at 0 0 90)
			(layer "F.Fab")
			(effects
				(font
					(size 1.27 1.27)
				)
			)
		)
		(duplicate_pad_numbers_are_jumpers no)
		(fp_line
			(start 0.7874 -0.4064)
			(end 0.7874 0.4064)
			(stroke
				(width 0.1524)
				(type default)
			)
			(layer "F.SilkS")
		)
		(fp_line
			(start -0.7874 -0.4064)
			(end 0.7874 -0.4064)
			(stroke
				(width 0.1524)
				(type default)
			)
			(layer "F.SilkS")
		)
		(fp_line
			(start 0.7874 0.4064)
			(end -0.7874 0.4064)
			(stroke
				(width 0.1524)
				(type default)
			)
			(layer "F.SilkS")
		)
		(fp_line
			(start -0.7874 0.4064)
			(end -0.7874 -0.4064)
			(stroke
				(width 0.1524)
				(type default)
			)
			(layer "F.SilkS")
		)
		(fp_line
			(start -0.12065 -0.305054)
			(end -0.12065 -0.2794)
			(stroke
				(width 0.1)
				(type default)
			)
			(layer "F.Fab")
		)
		(fp_line
			(start -0.67945 -0.305054)
			(end -0.12065 -0.305054)
			(stroke
				(width 0.1)
				(type default)
			)
			(layer "F.Fab")
		)
		(fp_line
			(start 0.67945 -0.3048)
			(end 0.67945 0.3048)
			(stroke
				(width 0.1)
				(type default)
			)
			(layer "F.Fab")
		)
		(fp_line
			(start 0.12065 -0.3048)
			(end 0.67945 -0.3048)
			(stroke
				(width 0.1)
				(type default)
			)
			(layer "F.Fab")
		)
		(fp_line
			(start 0.12065 -0.2794)
			(end 0.12065 -0.3048)
			(stroke
				(width 0.1)
				(type default)
			)
			(layer "F.Fab")
		)
		(fp_line
			(start -0.12065 -0.2794)
			(end 0.12065 -0.2794)
			(stroke
				(width 0.1)
				(type default)
			)
			(layer "F.Fab")
		)
		(fp_line
			(start 0.120396 0.2794)
			(end -0.12065 0.2794)
			(stroke
				(width 0.1)
				(type default)
			)
			(layer "F.Fab")
		)
		(fp_line
			(start -0.12065 0.2794)
			(end -0.12065 0.3048)
			(stroke
				(width 0.1)
				(type default)
			)
			(layer "F.Fab")
		)
		(fp_line
			(start 0.67945 0.3048)
			(end 0.120396 0.3048)
			(stroke
				(width 0.1)
				(type default)
			)
			(layer "F.Fab")
		)
		(fp_line
			(start 0.120396 0.3048)
			(end 0.120396 0.2794)
			(stroke
				(width 0.1)
				(type default)
			)
			(layer "F.Fab")
		)
		(fp_line
			(start -0.12065 0.3048)
			(end -0.67945 0.3048)
			(stroke
				(width 0.1)
				(type default)
			)
			(layer "F.Fab")
		)
		(fp_line
			(start -0.67945 0.3048)
			(end -0.67945 -0.305054)
			(stroke
				(width 0.1)
				(type default)
			)
			(layer "F.Fab")
		)
		(pad "1" smd circle
			(at -0.40005 0 90)
			(size 0 0)
			(layers "F.Cu" "F.Mask" "F.Paste")
			(net "P12V_NIC4_CO_IMON_VR")
		)
		(pad "2" smd circle
			(at 0.40005 0 90)
			(size 0 0)
			(layers "F.Cu" "F.Mask" "F.Paste")
			(net "GND")
		)
	)
	(footprint ""
		(layer "F.Cu")
		(at 83.109562 -356.244906 90)
		(property "Reference" "C105"
			(at 0 0 90)
			(layer "F.SilkS")
			(hide yes)
			(effects
				(font
					(size 1.27 1.27)
				)
			)
		)
		(property "Value" ""
			(at 0 0 90)
			(layer "F.Fab")
			(effects
				(font
					(size 1.27 1.27)
				)
			)
		)
		(duplicate_pad_numbers_are_jumpers no)
		(fp_line
			(start 0.299974 -0.150114)
			(end 0.299974 0.150114)
			(stroke
				(width 0.1)
				(type default)
			)
			(layer "F.Fab")
		)
		(fp_line
			(start -0.299974 -0.150114)
			(end 0.299974 -0.150114)
			(stroke
				(width 0.1)
				(type default)
			)
			(layer "F.Fab")
		)
		(fp_line
			(start 0.299974 0.150114)
			(end -0.299974 0.150114)
			(stroke
				(width 0.1)
				(type default)
			)
			(layer "F.Fab")
		)
		(fp_line
			(start -0.299974 0.150114)
			(end -0.299974 -0.150114)
			(stroke
				(width 0.1)
				(type default)
			)
			(layer "F.Fab")
		)
		(pad "1" smd rect
			(at -0.2667 0 90)
			(size 0.3048 0.381)
			(layers "F.Cu" "F.Mask" "F.Paste")
			(net "P5E_PEX0_STN5_TX_DP<91>")
		)
		(pad "2" smd rect
			(at 0.2667 0 90)
			(size 0.3048 0.381)
			(layers "F.Cu" "F.Mask" "F.Paste")
			(net "P5E_PEX0_STN5_TX_C_DP<91>")
		)
	)
	(footprint ""
		(layer "F.Cu")
		(at 425.728892 -343.952322 90)
		(property "Reference" "C2454"
			(at 0 0 90)
			(layer "F.SilkS")
			(hide yes)
			(effects
				(font
					(size 1.27 1.27)
				)
			)
		)
		(property "Value" ""
			(at 0 0 90)
			(layer "F.Fab")
			(effects
				(font
					(size 1.27 1.27)
				)
			)
		)
		(duplicate_pad_numbers_are_jumpers no)
		(fp_line
			(start 0.299974 -0.150114)
			(end 0.299974 0.150114)
			(stroke
				(width 0.1)
				(type default)
			)
			(layer "F.Fab")
		)
		(fp_line
			(start -0.299974 -0.150114)
			(end 0.299974 -0.150114)
			(stroke
				(width 0.1)
				(type default)
			)
			(layer "F.Fab")
		)
		(fp_line
			(start 0.299974 0.150114)
			(end -0.299974 0.150114)
			(stroke
				(width 0.1)
				(type default)
			)
			(layer "F.Fab")
		)
		(fp_line
			(start -0.299974 0.150114)
			(end -0.299974 -0.150114)
			(stroke
				(width 0.1)
				(type default)
			)
			(layer "F.Fab")
		)
		(pad "1" smd rect
			(at -0.2667 0 90)
			(size 0.3048 0.381)
			(layers "F.Cu" "F.Mask" "F.Paste")
			(net "P5E_PEX3_STN4_TX_DN<72>")
		)
		(pad "2" smd rect
			(at 0.2667 0 90)
			(size 0.3048 0.381)
			(layers "F.Cu" "F.Mask" "F.Paste")
			(net "P5E_PEX3_STN4_TX_C_DN<72>")
		)
	)
)
